# T6G (Grand Teton) — schematic netlist excerpt (pin names and nets, part order shuffled) for the footprints in the layout excerpt that follows; sources: Cadence DE-HDL packaged netlist, KiCad conversion of 04192023_DAF0TMB3IC0_F0TG_MB_C_brd_V02_OCP.brd

C439  Q_CAP  4.7UF 6.3V 20% X6S  pkg 0402  page 356 : A = P1V8_CPU1_RT_1D ; B = GND
R6234  Q_RES  160K 1% EMPTY  pkg 0402LF  page 267 : A = HSC_CSOUT ; B = A_HSC_HIGH

(kicad_pcb
	(version 20260206)
	(generator "pcbnew")
	(generator_version "10.0")
	(general
		(thickness 1.6)
		(legacy_teardrops no)
	)
	(paper "A4")
	(title_block
		(title "04192023_DAF0TMB3IC0_F0TG_MB_C_brd_V02_OCP.brd")
		(comment 1 "Grand Teton / footprints 6428-6429 of 8354")
	)
	(layers
		(0 "F.Cu" signal "TOP")
		(4 "In1.Cu" signal "GND")
		(6 "In2.Cu" signal "IN1")
		(8 "In3.Cu" signal "GND1")
		(10 "In4.Cu" signal "IN2")
		(12 "In5.Cu" signal "GND2")
		(14 "In6.Cu" signal "IN3")
		(16 "In7.Cu" signal "GND3")
		(18 "In8.Cu" signal "VCC")
		(20 "In9.Cu" signal "VCC1")
		(22 "In10.Cu" signal "GND4")
		(24 "In11.Cu" signal "IN4")
		(26 "In12.Cu" signal "GND5")
		(28 "In13.Cu" signal "IN5")
		(30 "In14.Cu" signal "GND6")
		(32 "In15.Cu" signal "IN6")
		(34 "In16.Cu" signal "GND7")
		(2 "B.Cu" signal "BOTTOM")
		(9 "F.Adhes" user "F.Adhesive")
		(11 "B.Adhes" user "B.Adhesive")
		(13 "F.Paste" user "Package Geometry/Pastemask Top")
		(15 "B.Paste" user "Package Geometry/Pastemask Bottom")
		(5 "F.SilkS" user "Ref Des/Silkscreen Top")
		(7 "B.SilkS" user "Ref Des/Silkscreen Bottom")
		(1 "F.Mask" user "Board Geometry/Soldermask Top")
		(3 "B.Mask" user "Board Geometry/Soldermask Bottom")
		(17 "Dwgs.User" user "User.Drawings")
		(19 "Cmts.User" user "User.Comments")
		(21 "Eco1.User" user "User.Eco1")
		(23 "Eco2.User" user "User.Eco2")
		(25 "Edge.Cuts" user "Board Geometry/Outline")
		(27 "Margin" user)
		(31 "F.CrtYd" user "Package Geometry/Place Bound Top")
		(29 "B.CrtYd" user "Package Geometry/Place Bound Bottom")
		(35 "F.Fab" user "Ref Des/Assembly Top")
		(33 "B.Fab" user "Ref Des/Assembly Bottom")
	)
	(footprint ""
		(layer "B.Cu")
		(at 139.152376 -386.745988 -90)
		(property "Reference" "C439"
			(at 0 0 90)
			(layer "B.SilkS")
			(hide yes)
			(effects
				(font
					(size 1.27 1.27)
				)
				(justify mirror)
			)
		)
		(property "Value" ""
			(at 0 0 90)
			(layer "B.Fab")
			(effects
				(font
					(size 1.27 1.27)
				)
				(justify mirror)
			)
		)
		(duplicate_pad_numbers_are_jumpers no)
		(fp_line
			(start -0.7874 0.4064)
			(end 0.7874 0.4064)
			(stroke
				(width 0.1524)
				(type default)
			)
			(layer "B.SilkS")
		)
		(fp_line
			(start 0.7874 0.4064)
			(end 0.7874 -0.4064)
			(stroke
				(width 0.1524)
				(type default)
			)
			(layer "B.SilkS")
		)
		(fp_line
			(start -0.7874 -0.4064)
			(end -0.7874 0.4064)
			(stroke
				(width 0.1524)
				(type default)
			)
			(layer "B.SilkS")
		)
		(fp_line
			(start 0.7874 -0.4064)
			(end -0.7874 -0.4064)
			(stroke
				(width 0.1524)
				(type default)
			)
			(layer "B.SilkS")
		)
		(fp_line
			(start -0.67945 0.3048)
			(end -0.120396 0.3048)
			(stroke
				(width 0.1)
				(type default)
			)
			(layer "B.Fab")
		)
		(fp_line
			(start -0.120396 0.3048)
			(end -0.120396 0.2794)
			(stroke
				(width 0.1)
				(type default)
			)
			(layer "B.Fab")
		)
		(fp_line
			(start 0.12065 0.3048)
			(end 0.67945 0.3048)
			(stroke
				(width 0.1)
				(type default)
			)
			(layer "B.Fab")
		)
		(fp_line
			(start 0.67945 0.3048)
			(end 0.67945 -0.305054)
			(stroke
				(width 0.1)
				(type default)
			)
			(layer "B.Fab")
		)
		(fp_line
			(start -0.120396 0.2794)
			(end 0.12065 0.2794)
			(stroke
				(width 0.1)
				(type default)
			)
			(layer "B.Fab")
		)
		(fp_line
			(start 0.12065 0.2794)
			(end 0.12065 0.3048)
			(stroke
				(width 0.1)
				(type default)
			)
			(layer "B.Fab")
		)
		(fp_line
			(start -0.12065 -0.2794)
			(end -0.12065 -0.3048)
			(stroke
				(width 0.1)
				(type default)
			)
			(layer "B.Fab")
		)
		(fp_line
			(start 0.12065 -0.2794)
			(end -0.12065 -0.2794)
			(stroke
				(width 0.1)
				(type default)
			)
			(layer "B.Fab")
		)
		(fp_line
			(start -0.67945 -0.3048)
			(end -0.67945 0.3048)
			(stroke
				(width 0.1)
				(type default)
			)
			(layer "B.Fab")
		)
		(fp_line
			(start -0.12065 -0.3048)
			(end -0.67945 -0.3048)
			(stroke
				(width 0.1)
				(type default)
			)
			(layer "B.Fab")
		)
		(fp_line
			(start 0.12065 -0.305054)
			(end 0.12065 -0.2794)
			(stroke
				(width 0.1)
				(type default)
			)
			(layer "B.Fab")
		)
		(fp_line
			(start 0.67945 -0.305054)
			(end 0.12065 -0.305054)
			(stroke
				(width 0.1)
				(type default)
			)
			(layer "B.Fab")
		)
		(pad "1" smd circle
			(at 0.40005 0 90)
			(size 0 0)
			(layers "B.Cu" "B.Mask" "B.Paste")
			(net "P1V8_CPU1_RT_1D")
		)
		(pad "2" smd circle
			(at -0.40005 0 90)
			(size 0 0)
			(layers "B.Cu" "B.Mask" "B.Paste")
			(net "GND")
		)
	)
	(footprint ""
		(layer "B.Cu")
		(at 182.880254 -424.39082)
		(property "Reference" "R6234"
			(at 0 0 0)
			(layer "B.SilkS")
			(hide yes)
			(effects
				(font
					(size 1.27 1.27)
				)
				(justify mirror)
			)
		)
		(property "Value" ""
			(at 0 0 0)
			(layer "B.Fab")
			(effects
				(font
					(size 1.27 1.27)
				)
				(justify mirror)
			)
		)
		(duplicate_pad_numbers_are_jumpers no)
		(fp_line
			(start -0.7874 -0.4064)
			(end -0.7874 0.4064)
			(stroke
				(width 0.1524)
				(type default)
			)
			(layer "B.SilkS")
		)
		(fp_line
			(start -0.7874 0.4064)
			(end 0.7874 0.4064)
			(stroke
				(width 0.1524)
				(type default)
			)
			(layer "B.SilkS")
		)
		(fp_line
			(start 0.7874 -0.4064)
			(end -0.7874 -0.4064)
			(stroke
				(width 0.1524)
				(type default)
			)
			(layer "B.SilkS")
		)
		(fp_line
			(start 0.7874 0.4064)
			(end 0.7874 -0.4064)
			(stroke
				(width 0.1524)
				(type default)
			)
			(layer "B.SilkS")
		)
		(fp_line
			(start -0.67945 -0.3048)
			(end -0.67945 0.3048)
			(stroke
				(width 0.1)
				(type default)
			)
			(layer "B.Fab")
		)
		(fp_line
			(start -0.67945 0.3048)
			(end -0.120396 0.3048)
			(stroke
				(width 0.1)
				(type default)
			)
			(layer "B.Fab")
		)
		(fp_line
			(start -0.12065 -0.3048)
			(end -0.67945 -0.3048)
			(stroke
				(width 0.1)
				(type default)
			)
			(layer "B.Fab")
		)
		(fp_line
			(start -0.12065 -0.2794)
			(end -0.12065 -0.3048)
			(stroke
				(width 0.1)
				(type default)
			)
			(layer "B.Fab")
		)
		(fp_line
			(start -0.120396 0.2794)
			(end 0.12065 0.2794)
			(stroke
				(width 0.1)
				(type default)
			)
			(layer "B.Fab")
		)
		(fp_line
			(start -0.120396 0.3048)
			(end -0.120396 0.2794)
			(stroke
				(width 0.1)
				(type default)
			)
			(layer "B.Fab")
		)
		(fp_line
			(start 0.12065 -0.305054)
			(end 0.12065 -0.2794)
			(stroke
				(width 0.1)
				(type default)
			)
			(layer "B.Fab")
		)
		(fp_line
			(start 0.12065 -0.2794)
			(end -0.12065 -0.2794)
			(stroke
				(width 0.1)
				(type default)
			)
			(layer "B.Fab")
		)
		(fp_line
			(start 0.12065 0.2794)
			(end 0.12065 0.3048)
			(stroke
				(width 0.1)
				(type default)
			)
			(layer "B.Fab")
		)
		(fp_line
			(start 0.12065 0.3048)
			(end 0.67945 0.3048)
			(stroke
				(width 0.1)
				(type default)
			)
			(layer "B.Fab")
		)
		(fp_line
			(start 0.67945 -0.305054)
			(end 0.12065 -0.305054)
			(stroke
				(width 0.1)
				(type default)
			)
			(layer "B.Fab")
		)
		(fp_line
			(start 0.67945 0.3048)
			(end 0.67945 -0.305054)
			(stroke
				(width 0.1)
				(type default)
			)
			(layer "B.Fab")
		)
		(pad "1" smd circle
			(at 0.40005 0 180)
			(size 0 0)
			(layers "B.Cu" "B.Mask" "B.Paste")
			(net "HSC_CSOUT")
		)
		(pad "2" smd circle
			(at -0.40005 0 180)
			(size 0 0)
			(layers "B.Cu" "B.Mask" "B.Paste")
			(net "A_HSC_HIGH")
		)
	)
)
